G04 ================== begin FILE IDENTIFICATION RECORD ==================*
G04 Layout Name:  13919-sa.brd*
G04 Film Name:    TMASK*
G04 File Format:  Gerber RS274X*
G04 File Origin:  Cadence Allegro 16.5-S039*
G04 Origin Date:  Fri Nov 22 15:27:01 2013*
G04 *
G04 Layer:  VIA CLASS/SOLDERMASK_TOP*
G04 Layer:  PIN/SOLDERMASK_TOP*
G04 Layer:  PACKAGE GEOMETRY/SOLDERMASK_TOP*
G04 Layer:  DRAWING FORMAT/LAYER_PCB_STORY*
G04 Layer:  DRAWING FORMAT/LAYER_SOLDER_T*
G04 Layer:  BOARD GEOMETRY/SOLDERMASK_TOP*
G04 *
G04 Offset:    (0.00 0.00)*
G04 Mirror:    No*
G04 Mode:      Positive*
G04 Rotation:  0*
G04 FullContactRelief:  No*
G04 UndefLineWidth:     6.00*
G04 ================== end FILE IDENTIFICATION RECORD ====================*
%FSLAX35Y35*MOIN*%
%IR0*IPPOS*OFA0.00000B0.00000*MIA0B0*SFA1.00000B1.00000*%
%ADD14R,.028X.126*%
%ADD12C,.043*%
%ADD10R,.028X.165*%
%ADD11C,.093*%
%ADD13C,.086*%
%ADD15C,.02*%
%ADD16C,.006*%
G75*
%LPD*%
G75*
G36*
G01X20763Y-300D02*
Y22012D01*
X353253D01*
Y-300D01*
X20763D01*
G37*
G54D10*
X23622Y13762D03*
X27559D03*
X31496D03*
X35433D03*
X39370D03*
X43307D03*
X47244D03*
X51181D03*
X55118D03*
X59055D03*
X62992D03*
X66929D03*
X70866D03*
X74803D03*
X78740D03*
X82677D03*
X86614D03*
X90551D03*
X94488D03*
X98425D03*
X102362D03*
X106299D03*
X110236D03*
X114173D03*
X118110D03*
X122047D03*
X125984D03*
X129921D03*
X133858D03*
X137795D03*
X141732D03*
X145669D03*
X149606D03*
X153543D03*
X157480D03*
X161417D03*
X165354D03*
X169291D03*
X173228D03*
X177165D03*
X181102D03*
X185039D03*
X188976D03*
X192913D03*
X196850D03*
X200787D03*
X204724D03*
X208661D03*
X212598D03*
X216535D03*
X220472D03*
X224409D03*
X228346D03*
X232283D03*
X236220D03*
X240157D03*
X244094D03*
X248031D03*
X251968D03*
X255905D03*
X259842D03*
X263779D03*
X267716D03*
X271653D03*
X275590D03*
X279527D03*
X283464D03*
X287401D03*
X291338D03*
X295275D03*
X299212D03*
X311024D03*
X314961D03*
X318898D03*
X322835D03*
X326772D03*
X330709D03*
X334646D03*
X338583D03*
X342520D03*
X346457D03*
G54D11*
X16538Y78346D03*
X304528D03*
G54D12*
X47243Y65551D03*
X43308Y73426D03*
X39373Y65551D03*
X35433Y73426D03*
X31498Y65551D03*
X27558Y73426D03*
X23623Y65551D03*
X47243Y91141D03*
X43308Y83266D03*
X39373Y91141D03*
X35433Y83266D03*
X31498Y91141D03*
X27558Y83266D03*
X23623Y91141D03*
X110238Y65551D03*
X106298Y73426D03*
X102363Y65551D03*
X98428Y73426D03*
X94488Y65551D03*
X90553Y73426D03*
X86613Y65551D03*
X82678Y73426D03*
X78743Y65551D03*
X74803Y73426D03*
X70868Y65551D03*
X66928Y73426D03*
X62993Y65551D03*
X59058Y73426D03*
X55118Y65551D03*
X51183Y73426D03*
X110238Y91141D03*
X106298Y83266D03*
X102363Y91141D03*
X98428Y83266D03*
X94488Y91141D03*
X90553Y83266D03*
X86613Y91141D03*
X82678Y83266D03*
X78743Y91141D03*
X74803Y83266D03*
X70868Y91141D03*
X66928Y83266D03*
X62993Y91141D03*
X59058Y83266D03*
X55118Y91141D03*
X51183Y83266D03*
X169293Y73426D03*
X165353Y65551D03*
X161418Y73426D03*
X157483Y65551D03*
X153543Y73426D03*
X149608Y65551D03*
X145668Y73426D03*
X141733Y65551D03*
X137798Y73426D03*
X133858Y65551D03*
X129923Y73426D03*
X125983Y65551D03*
X122048Y73426D03*
X118113Y65551D03*
X114173Y73426D03*
X169293Y83266D03*
X165353Y91141D03*
X161418Y83266D03*
X157483Y91141D03*
X153543Y83266D03*
X149608Y91141D03*
X145668Y83266D03*
X141733Y91141D03*
X137798Y83266D03*
X133858Y91141D03*
X129923Y83266D03*
X125983Y91141D03*
X122048Y83266D03*
X118113Y91141D03*
X114173Y83266D03*
X232283Y73426D03*
X228348Y65551D03*
X224408Y73426D03*
X220473Y65551D03*
X216538Y73426D03*
X212598Y65551D03*
X208663Y73426D03*
X204723Y65551D03*
X200788Y73426D03*
X196853Y65551D03*
X192913Y73426D03*
X188978Y65551D03*
X185038Y73426D03*
X181103Y65551D03*
X177168Y73426D03*
X173228Y65551D03*
X232283Y83266D03*
X228348Y91141D03*
X224408Y83266D03*
X220473Y91141D03*
X216538Y83266D03*
X212598Y91141D03*
X208663Y83266D03*
X204723Y91141D03*
X200788Y83266D03*
X196853Y91141D03*
X192913Y83266D03*
X188978Y91141D03*
X185038Y83266D03*
X181103Y91141D03*
X177168Y83266D03*
X173228Y91141D03*
X291338Y65551D03*
X287403Y73426D03*
X283463Y65551D03*
X279528Y73426D03*
X275593Y65551D03*
X271653Y73426D03*
X267718Y65551D03*
X263778Y73426D03*
X259843Y65551D03*
X255908Y73426D03*
X251968Y65551D03*
X248033Y73426D03*
X244093Y65551D03*
X240158Y73426D03*
X236223Y65551D03*
X291338Y91141D03*
X287403Y83266D03*
X283463Y91141D03*
X279528Y83266D03*
X275593Y91141D03*
X271653Y83266D03*
X267718Y91141D03*
X263778Y83266D03*
X259843Y91141D03*
X255908Y83266D03*
X251968Y91141D03*
X248033Y83266D03*
X244093Y91141D03*
X240158Y83266D03*
X236223Y91141D03*
X350393Y73426D03*
X346458Y65551D03*
X342518Y73426D03*
X338583Y65551D03*
X334648Y73426D03*
X330708Y65551D03*
X326773Y73426D03*
X322833Y65551D03*
X318898Y73426D03*
X314963Y65551D03*
X311023Y73426D03*
X299213Y65551D03*
X295278Y73426D03*
X350393Y83266D03*
X346458Y91141D03*
X342518Y83266D03*
X338583Y91141D03*
X334648Y83266D03*
X330708Y91141D03*
X326773Y83266D03*
X322833Y91141D03*
X318898Y83266D03*
X314963Y91141D03*
X311023Y83266D03*
X299213Y91141D03*
X295278Y83266D03*
G54D13*
X8950Y97440D03*
X8750Y50860D03*
X-2462Y651994D03*
X364570Y96910D03*
X758452Y17317D03*
X755722Y677788D03*
G54D14*
X350394Y15712D03*
G54D15*
G01X-67189Y-77263D02*
G02I-12000J0D01*
G01X-72339D02*
G02I-6850J0D01*
G01X-79189Y-93263D02*
Y-61263D01*
G01X-63189Y-77263D02*
X-95189D01*
G01X-63189Y-93263D02*
Y-173263D01*
G01D02*
X1156611D01*
G01X-63189Y-93263D02*
X1156611D01*
G01X-63189Y-128763D02*
X1156611D01*
G01X369111Y-93263D02*
Y-173263D01*
G01X506611Y-93263D02*
Y-173263D01*
G01X621611Y-93263D02*
Y-173263D01*
G01X789111Y-93263D02*
Y-173263D01*
G01X959111Y-93263D02*
Y-173263D01*
G01X1156611Y-93263D02*
Y-173263D01*
G01X1184611Y-77263D02*
G02I-12000J0D01*
G01X1179461D02*
G02I-6850J0D01*
G01X1172611Y-93263D02*
Y-61263D01*
G01X1188611Y-77263D02*
X1156611D01*
G54D16*
G01X-44374Y-163263D02*
Y-145763D01*
G01X-35204D02*
Y-163263D01*
G01Y-154513D02*
X-44374D01*
G01X-22289Y-163263D02*
X-23599Y-162971D01*
X-24909Y-161805D01*
X-25783Y-159763D01*
X-26219Y-157430D01*
X-25783Y-155096D01*
X-24909Y-153055D01*
X-23599Y-151888D01*
X-22289Y-151597D01*
X-20979Y-151888D01*
X-19669Y-153055D01*
X-18796Y-155096D01*
X-18577Y-157430D01*
X-18796Y-159763D01*
X-19669Y-161805D01*
X-20979Y-162971D01*
X-22289Y-163263D01*
G01X-8501D02*
Y-151597D01*
G01Y-154513D02*
X-7627Y-153055D01*
X-6317Y-151888D01*
X-4571Y-151597D01*
X-3043Y-151888D01*
X-1732Y-153055D01*
X-1077Y-155096D01*
Y-163263D01*
G01X9436Y-155388D02*
X16423D01*
X15768Y-153346D01*
X14676Y-152180D01*
X13148Y-151597D01*
X11619Y-151888D01*
X10309Y-152763D01*
X9436Y-154805D01*
X8999Y-156555D01*
Y-158305D01*
X9436Y-160055D01*
X10528Y-161805D01*
X11838Y-162971D01*
X13366Y-163263D01*
X14894Y-162680D01*
X16423Y-160930D01*
G01X25626Y-168513D02*
X26936Y-169096D01*
X28683Y-168513D01*
X29774Y-167347D01*
X30648Y-165888D01*
X31957Y-161222D01*
X34796Y-151597D01*
G01X27809D02*
X31957Y-161222D01*
G01X66957Y-153930D02*
X67831Y-153055D01*
X68486Y-151597D01*
X68923Y-149554D01*
X68486Y-147805D01*
X67613Y-146638D01*
X66084Y-145763D01*
X60189D01*
Y-163263D01*
X67394D01*
X68923Y-162097D01*
X69796Y-160346D01*
X70233Y-158305D01*
X69796Y-156263D01*
X68486Y-154513D01*
X66957Y-153930D01*
X60189D01*
G01X86641Y-163263D02*
Y-151597D01*
G01Y-153638D02*
X85768Y-152472D01*
X84457Y-151888D01*
X82929Y-151597D01*
X81401Y-152180D01*
X80091Y-153346D01*
X79217Y-155096D01*
X78781Y-157430D01*
X79217Y-159763D01*
X80091Y-161513D01*
X81401Y-162680D01*
X82929Y-163263D01*
X84457Y-162971D01*
X85768Y-162097D01*
X86641Y-160930D01*
G01X104141Y-145763D02*
Y-163263D01*
G01Y-160639D02*
X103268Y-162097D01*
X101957Y-162971D01*
X100429Y-163263D01*
X98683Y-162680D01*
X97373Y-161222D01*
X96499Y-159472D01*
X96281Y-157430D01*
X96499Y-155388D01*
X97373Y-153638D01*
X98683Y-152180D01*
X100429Y-151597D01*
X101957Y-151888D01*
X103049Y-152472D01*
X104141Y-153638D01*
G01X114654Y-167638D02*
X116183Y-168805D01*
X117929Y-169096D01*
X119457Y-168805D01*
X120768Y-167347D01*
X121641Y-165305D01*
Y-151597D01*
G01Y-153930D02*
X120768Y-152763D01*
X119457Y-151888D01*
X117929Y-151597D01*
X116183Y-152180D01*
X115091Y-153346D01*
X114217Y-155388D01*
X113781Y-157430D01*
X113999Y-159180D01*
X114873Y-161222D01*
X116183Y-162680D01*
X117929Y-163263D01*
X119239Y-162971D01*
X120768Y-161805D01*
X121641Y-160639D01*
G01X131936Y-155388D02*
X138923D01*
X138268Y-153346D01*
X137176Y-152180D01*
X135648Y-151597D01*
X134119Y-151888D01*
X132809Y-152763D01*
X131936Y-154805D01*
X131499Y-156555D01*
Y-158305D01*
X131936Y-160055D01*
X133028Y-161805D01*
X134338Y-162971D01*
X135866Y-163263D01*
X137394Y-162680D01*
X138923Y-160930D01*
G01X149654Y-163263D02*
Y-151597D01*
G01Y-153930D02*
X150746Y-152763D01*
X151838Y-151888D01*
X153366Y-151597D01*
X154457Y-151888D01*
X155768Y-152763D01*
G01X183344Y-163263D02*
Y-145763D01*
X188803D01*
X190549Y-146638D01*
X191641Y-147805D01*
X192078Y-150138D01*
X191641Y-152472D01*
X190331Y-153930D01*
X188803Y-154805D01*
X183344D01*
G01X188803D02*
X192078Y-163263D01*
G01X205211Y-151597D02*
Y-163263D01*
G01Y-146930D02*
X204774Y-146638D01*
Y-146055D01*
X205211Y-145763D01*
X205648Y-146055D01*
Y-146638D01*
X205211Y-146930D01*
G01X219436Y-161222D02*
X220528Y-162388D01*
X222056Y-163263D01*
X223366D01*
X224676Y-162680D01*
X225549Y-161805D01*
X225986Y-160639D01*
X225768Y-158888D01*
X224894Y-158013D01*
X220964Y-156263D01*
X220091Y-154221D01*
X220528Y-152763D01*
X221401Y-151888D01*
X222711Y-151597D01*
X224021Y-151888D01*
X225331Y-152763D01*
G01X236936Y-155388D02*
X243923D01*
X243268Y-153346D01*
X242176Y-152180D01*
X240648Y-151597D01*
X239119Y-151888D01*
X237809Y-152763D01*
X236936Y-154805D01*
X236499Y-156555D01*
Y-158305D01*
X236936Y-160055D01*
X238028Y-161805D01*
X239338Y-162971D01*
X240866Y-163263D01*
X242394Y-162680D01*
X243923Y-160930D01*
G01X254654Y-163263D02*
Y-151597D01*
G01Y-153930D02*
X255746Y-152763D01*
X256838Y-151888D01*
X258366Y-151597D01*
X259457Y-151888D01*
X260768Y-152763D01*
G01X297514Y-147222D02*
X296204Y-146346D01*
X294676Y-145763D01*
X292929D01*
X290964Y-146638D01*
X289436Y-148096D01*
X288344Y-149847D01*
X287471Y-152763D01*
X287252Y-155388D01*
X287689Y-158013D01*
X288344Y-159763D01*
X289654Y-161513D01*
X291183Y-162680D01*
X292711Y-163263D01*
X294239D01*
X295768Y-162680D01*
X297078Y-161805D01*
X298170Y-160639D01*
G01X314141Y-163263D02*
Y-151597D01*
G01Y-153638D02*
X313268Y-152472D01*
X311957Y-151888D01*
X310429Y-151597D01*
X308901Y-152180D01*
X307591Y-153346D01*
X306717Y-155096D01*
X306281Y-157430D01*
X306717Y-159763D01*
X307591Y-161513D01*
X308901Y-162680D01*
X310429Y-163263D01*
X311957Y-162971D01*
X313268Y-162097D01*
X314141Y-160930D01*
G01X324654Y-163263D02*
Y-151597D01*
G01Y-153930D02*
X325746Y-152763D01*
X326838Y-151888D01*
X328366Y-151597D01*
X329457Y-151888D01*
X330768Y-152763D01*
G01X349141Y-145763D02*
Y-163263D01*
G01Y-160639D02*
X348268Y-162097D01*
X346957Y-162971D01*
X345429Y-163263D01*
X343683Y-162680D01*
X342373Y-161222D01*
X341499Y-159472D01*
X341281Y-157430D01*
X341499Y-155388D01*
X342373Y-153638D01*
X343683Y-152180D01*
X345429Y-151597D01*
X346957Y-151888D01*
X348049Y-152472D01*
X349141Y-153638D01*
G01X112034Y-118263D02*
Y-100763D01*
X117711Y-115346D01*
X123388Y-100763D01*
Y-118263D01*
G01X135211D02*
X133901Y-117971D01*
X132591Y-116805D01*
X131717Y-114763D01*
X131281Y-112430D01*
X131717Y-110096D01*
X132591Y-108055D01*
X133901Y-106888D01*
X135211Y-106597D01*
X136521Y-106888D01*
X137831Y-108055D01*
X138704Y-110096D01*
X138923Y-112430D01*
X138704Y-114763D01*
X137831Y-116805D01*
X136521Y-117971D01*
X135211Y-118263D01*
G01X156641Y-100763D02*
Y-118263D01*
G01Y-115639D02*
X155768Y-117097D01*
X154457Y-117971D01*
X152929Y-118263D01*
X151183Y-117680D01*
X149873Y-116222D01*
X148999Y-114472D01*
X148781Y-112430D01*
X148999Y-110388D01*
X149873Y-108638D01*
X151183Y-107180D01*
X152929Y-106597D01*
X154457Y-106888D01*
X155549Y-107472D01*
X156641Y-108638D01*
G01X166936Y-110388D02*
X173923D01*
X173268Y-108346D01*
X172176Y-107180D01*
X170648Y-106597D01*
X169119Y-106888D01*
X167809Y-107763D01*
X166936Y-109805D01*
X166499Y-111555D01*
Y-113305D01*
X166936Y-115055D01*
X168028Y-116805D01*
X169338Y-117971D01*
X170866Y-118263D01*
X172394Y-117680D01*
X173923Y-115930D01*
G01X187711Y-118263D02*
Y-100763D01*
G01X402811Y-163263D02*
Y-145763D01*
X400191Y-149263D01*
G01Y-163263D02*
X405431D01*
G01X415508Y-159763D02*
X416817Y-161805D01*
X418564Y-162971D01*
X420529Y-163263D01*
X422276Y-162971D01*
X424023Y-161513D01*
X425114Y-159763D01*
X425333Y-158013D01*
X424896Y-155972D01*
X423368Y-154513D01*
X421839Y-153930D01*
X419874D01*
G01X421839D02*
X423149Y-153055D01*
X424241Y-151597D01*
X424678Y-149847D01*
X424241Y-148096D01*
X423149Y-146638D01*
X421184Y-145763D01*
X419219Y-146055D01*
X417254Y-147222D01*
G01X434099Y-161222D02*
X435628Y-162680D01*
X437374Y-163263D01*
X439121Y-162680D01*
X440649Y-160930D01*
X441741Y-158305D01*
X442178Y-155680D01*
Y-152472D01*
X441741Y-149847D01*
X440649Y-147513D01*
X439339Y-146346D01*
X437811Y-145763D01*
X436064Y-146346D01*
X434754Y-147513D01*
X433881Y-149263D01*
X433444Y-151597D01*
X433881Y-153638D01*
X434973Y-155680D01*
X436283Y-156847D01*
X437811Y-157138D01*
X439557Y-156555D01*
X440868Y-155096D01*
X442178Y-152472D01*
G01X455311Y-163263D02*
Y-145763D01*
X452691Y-149263D01*
G01Y-163263D02*
X457931D01*
G01X469099Y-161222D02*
X470628Y-162680D01*
X472374Y-163263D01*
X474121Y-162680D01*
X475649Y-160930D01*
X476741Y-158305D01*
X477178Y-155680D01*
Y-152472D01*
X476741Y-149847D01*
X475649Y-147513D01*
X474339Y-146346D01*
X472811Y-145763D01*
X471064Y-146346D01*
X469754Y-147513D01*
X468881Y-149263D01*
X468444Y-151597D01*
X468881Y-153638D01*
X469973Y-155680D01*
X471283Y-156847D01*
X472811Y-157138D01*
X474557Y-156555D01*
X475868Y-155096D01*
X477178Y-152472D01*
G01X389694Y-118263D02*
Y-100763D01*
X394934D01*
X396681Y-101638D01*
X397991Y-103680D01*
X398428Y-106013D01*
X397991Y-108346D01*
X396899Y-110096D01*
X394934Y-110972D01*
X389694D01*
G01X416364Y-102222D02*
X415054Y-101346D01*
X413526Y-100763D01*
X411779D01*
X409814Y-101638D01*
X408286Y-103096D01*
X407194Y-104847D01*
X406321Y-107763D01*
X406102Y-110388D01*
X406539Y-113013D01*
X407194Y-114763D01*
X408504Y-116513D01*
X410033Y-117680D01*
X411561Y-118263D01*
X413089D01*
X414618Y-117680D01*
X415928Y-116805D01*
X417020Y-115639D01*
G01X430807Y-108930D02*
X431681Y-108055D01*
X432336Y-106597D01*
X432773Y-104554D01*
X432336Y-102805D01*
X431463Y-101638D01*
X429934Y-100763D01*
X424039D01*
Y-118263D01*
X431244D01*
X432773Y-117097D01*
X433646Y-115346D01*
X434083Y-113305D01*
X433646Y-111263D01*
X432336Y-109513D01*
X430807Y-108930D01*
X424039D01*
G01X440011Y-124096D02*
X453111D01*
G01X459039Y-118263D02*
Y-100763D01*
X469083Y-118263D01*
Y-100763D01*
G01X481561Y-118263D02*
X479814Y-117971D01*
X478286Y-116805D01*
X476976Y-115055D01*
X476102Y-113013D01*
X475666Y-110680D01*
Y-108346D01*
X476102Y-106013D01*
X476976Y-103971D01*
X478286Y-102222D01*
X479814Y-101055D01*
X481561Y-100763D01*
X483307Y-101055D01*
X484836Y-102222D01*
X486146Y-103971D01*
X487020Y-106013D01*
X487456Y-108346D01*
Y-110680D01*
X487020Y-113013D01*
X486146Y-115055D01*
X484836Y-116805D01*
X483307Y-117971D01*
X481561Y-118263D01*
G01X532402Y-100763D02*
X537861Y-118263D01*
X543320Y-100763D01*
G01X559728Y-118263D02*
X550994D01*
Y-100763D01*
X559728D01*
G01X556234Y-109221D02*
X550994D01*
G01X568494Y-118263D02*
Y-100763D01*
X573953D01*
X575699Y-101638D01*
X576791Y-102805D01*
X577228Y-105138D01*
X576791Y-107472D01*
X575481Y-108930D01*
X573953Y-109805D01*
X568494D01*
G01X573953D02*
X577228Y-118263D01*
G01X590361Y-118846D02*
X589924Y-118555D01*
Y-117971D01*
X590361Y-117680D01*
X590798Y-117971D01*
Y-118555D01*
X590361Y-118846D01*
G01X550776Y-160930D02*
X552523Y-162388D01*
X554488Y-163263D01*
X556234D01*
X557981Y-162388D01*
X559291Y-160930D01*
X559946Y-158888D01*
X559509Y-156847D01*
X558418Y-155096D01*
X556453Y-153930D01*
X553833Y-153346D01*
X552304Y-152180D01*
X551649Y-150138D01*
X552086Y-148096D01*
X553178Y-146638D01*
X554706Y-145763D01*
X556234D01*
X557763Y-146346D01*
X559073Y-147805D01*
G01X567402Y-163263D02*
X572861Y-145763D01*
X578320Y-163263D01*
G01X576354Y-157138D02*
X569367D01*
G01X670311Y-145763D02*
Y-163263D01*
G01X665289Y-145763D02*
X675333D01*
G01X682134Y-163263D02*
Y-145763D01*
X687811Y-160346D01*
X693488Y-145763D01*
Y-163263D01*
G01X699852D02*
X705311Y-145763D01*
X710770Y-163263D01*
G01X708804Y-157138D02*
X701817D01*
G01X718226Y-160930D02*
X719973Y-162388D01*
X721938Y-163263D01*
X723684D01*
X725431Y-162388D01*
X726741Y-160930D01*
X727396Y-158888D01*
X726959Y-156847D01*
X725868Y-155096D01*
X723903Y-153930D01*
X721283Y-153346D01*
X719754Y-152180D01*
X719099Y-150138D01*
X719536Y-148096D01*
X720628Y-146638D01*
X722156Y-145763D01*
X723684D01*
X725213Y-146346D01*
X726523Y-147805D01*
G01X735508Y-163263D02*
Y-145763D01*
G01X743804D02*
X735508Y-156555D01*
G01X745114Y-163263D02*
X739219Y-151597D01*
G01X665944Y-100763D02*
Y-118263D01*
X674678D01*
G01X691741D02*
Y-106597D01*
G01Y-108638D02*
X690868Y-107472D01*
X689557Y-106888D01*
X688029Y-106597D01*
X686501Y-107180D01*
X685191Y-108346D01*
X684317Y-110096D01*
X683881Y-112430D01*
X684317Y-114763D01*
X685191Y-116513D01*
X686501Y-117680D01*
X688029Y-118263D01*
X689557Y-117971D01*
X690868Y-117097D01*
X691741Y-115930D01*
G01X700726Y-123513D02*
X702036Y-124096D01*
X703783Y-123513D01*
X704874Y-122347D01*
X705748Y-120888D01*
X707057Y-116222D01*
X709896Y-106597D01*
G01X702909D02*
X707057Y-116222D01*
G01X719536Y-110388D02*
X726523D01*
X725868Y-108346D01*
X724776Y-107180D01*
X723248Y-106597D01*
X721719Y-106888D01*
X720409Y-107763D01*
X719536Y-109805D01*
X719099Y-111555D01*
Y-113305D01*
X719536Y-115055D01*
X720628Y-116805D01*
X721938Y-117971D01*
X723466Y-118263D01*
X724994Y-117680D01*
X726523Y-115930D01*
G01X737254Y-118263D02*
Y-106597D01*
G01Y-108930D02*
X738346Y-107763D01*
X739438Y-106888D01*
X740966Y-106597D01*
X742057Y-106888D01*
X743368Y-107763D01*
G01X808058Y-118263D02*
Y-100763D01*
X812424D01*
X814171Y-101638D01*
X815481Y-102805D01*
X816573Y-104554D01*
X817446Y-106597D01*
X817664Y-109513D01*
X817446Y-112430D01*
X816573Y-114472D01*
X815481Y-116222D01*
X814171Y-117388D01*
X812424Y-118263D01*
X808058D01*
G01X827086Y-110388D02*
X834073D01*
X833418Y-108346D01*
X832326Y-107180D01*
X830798Y-106597D01*
X829269Y-106888D01*
X827959Y-107763D01*
X827086Y-109805D01*
X826649Y-111555D01*
Y-113305D01*
X827086Y-115055D01*
X828178Y-116805D01*
X829488Y-117971D01*
X831016Y-118263D01*
X832544Y-117680D01*
X834073Y-115930D01*
G01X844586Y-116222D02*
X845678Y-117388D01*
X847206Y-118263D01*
X848516D01*
X849826Y-117680D01*
X850699Y-116805D01*
X851136Y-115639D01*
X850918Y-113888D01*
X850044Y-113013D01*
X846114Y-111263D01*
X845241Y-109221D01*
X845678Y-107763D01*
X846551Y-106888D01*
X847861Y-106597D01*
X849171Y-106888D01*
X850481Y-107763D01*
G01X865361Y-106597D02*
Y-118263D01*
G01Y-101930D02*
X864924Y-101638D01*
Y-101055D01*
X865361Y-100763D01*
X865798Y-101055D01*
Y-101638D01*
X865361Y-101930D01*
G01X879804Y-122638D02*
X881333Y-123805D01*
X883079Y-124096D01*
X884607Y-123805D01*
X885918Y-122347D01*
X886791Y-120305D01*
Y-106597D01*
G01Y-108930D02*
X885918Y-107763D01*
X884607Y-106888D01*
X883079Y-106597D01*
X881333Y-107180D01*
X880241Y-108346D01*
X879367Y-110388D01*
X878931Y-112430D01*
X879149Y-114180D01*
X880023Y-116222D01*
X881333Y-117680D01*
X883079Y-118263D01*
X884389Y-117971D01*
X885918Y-116805D01*
X886791Y-115639D01*
G01X896649Y-118263D02*
Y-106597D01*
G01Y-109513D02*
X897523Y-108055D01*
X898833Y-106888D01*
X900579Y-106597D01*
X902107Y-106888D01*
X903418Y-108055D01*
X904073Y-110096D01*
Y-118263D01*
G01X914586Y-110388D02*
X921573D01*
X920918Y-108346D01*
X919826Y-107180D01*
X918298Y-106597D01*
X916769Y-106888D01*
X915459Y-107763D01*
X914586Y-109805D01*
X914149Y-111555D01*
Y-113305D01*
X914586Y-115055D01*
X915678Y-116805D01*
X916988Y-117971D01*
X918516Y-118263D01*
X920044Y-117680D01*
X921573Y-115930D01*
G01X932304Y-118263D02*
Y-106597D01*
G01Y-108930D02*
X933396Y-107763D01*
X934488Y-106888D01*
X936016Y-106597D01*
X937107Y-106888D01*
X938418Y-107763D01*
G01X853991Y-145763D02*
X859231D01*
G01X856611D02*
Y-163263D01*
G01X853991D02*
X859231D01*
G01X868652Y-145763D02*
X874111Y-163263D01*
X879570Y-145763D01*
G01X891611Y-163263D02*
Y-155388D01*
X887244Y-145763D01*
G01X895978D02*
X891611Y-155388D01*
G01X979061Y-163263D02*
Y-145763D01*
X976441Y-149263D01*
G01Y-163263D02*
X981681D01*
G01X996561D02*
Y-145763D01*
X993941Y-149263D01*
G01Y-163263D02*
X999181D01*
G01X1010131Y-163846D02*
X1017991Y-145763D01*
G01X1027413Y-148680D02*
X1028723Y-146930D01*
X1030251Y-146055D01*
X1031998Y-145763D01*
X1034181Y-146346D01*
X1035709Y-147805D01*
X1036146Y-149554D01*
X1035928Y-151305D01*
X1035054Y-152763D01*
X1030688Y-155680D01*
X1028723Y-157721D01*
X1027413Y-160639D01*
X1026976Y-163263D01*
X1036146D01*
G01X1044913Y-148680D02*
X1046223Y-146930D01*
X1047751Y-146055D01*
X1049498Y-145763D01*
X1051681Y-146346D01*
X1053209Y-147805D01*
X1053646Y-149554D01*
X1053428Y-151305D01*
X1052554Y-152763D01*
X1048188Y-155680D01*
X1046223Y-157721D01*
X1044913Y-160639D01*
X1044476Y-163263D01*
X1053646D01*
G01X1062631Y-163846D02*
X1070491Y-145763D01*
G01X1079913Y-148680D02*
X1081223Y-146930D01*
X1082751Y-146055D01*
X1084498Y-145763D01*
X1086681Y-146346D01*
X1088209Y-147805D01*
X1088646Y-149554D01*
X1088428Y-151305D01*
X1087554Y-152763D01*
X1083188Y-155680D01*
X1081223Y-157721D01*
X1079913Y-160639D01*
X1079476Y-163263D01*
X1088646D01*
G01X1101561Y-145763D02*
X1099814Y-146346D01*
X1098504Y-147805D01*
X1097631Y-149554D01*
X1096976Y-151888D01*
X1096758Y-154513D01*
X1096976Y-157138D01*
X1097631Y-159472D01*
X1098504Y-161222D01*
X1099814Y-162680D01*
X1101561Y-163263D01*
X1103307Y-162680D01*
X1104618Y-161222D01*
X1105491Y-159472D01*
X1106146Y-157138D01*
X1106364Y-154513D01*
X1106146Y-151888D01*
X1105491Y-149554D01*
X1104618Y-147805D01*
X1103307Y-146346D01*
X1101561Y-145763D01*
G01X1119061Y-163263D02*
Y-145763D01*
X1116441Y-149263D01*
G01Y-163263D02*
X1121681D01*
G01X1131758Y-159763D02*
X1133067Y-161805D01*
X1134814Y-162971D01*
X1136779Y-163263D01*
X1138526Y-162971D01*
X1140273Y-161513D01*
X1141364Y-159763D01*
X1141583Y-158013D01*
X1141146Y-155972D01*
X1139618Y-154513D01*
X1138089Y-153930D01*
X1136124D01*
G01X1138089D02*
X1139399Y-153055D01*
X1140491Y-151597D01*
X1140928Y-149847D01*
X1140491Y-148096D01*
X1139399Y-146638D01*
X1137434Y-145763D01*
X1135469Y-146055D01*
X1133504Y-147222D01*
G01X1026758Y-118263D02*
Y-100763D01*
X1031124D01*
X1032871Y-101638D01*
X1034181Y-102805D01*
X1035273Y-104554D01*
X1036146Y-106597D01*
X1036364Y-109513D01*
X1036146Y-112430D01*
X1035273Y-114472D01*
X1034181Y-116222D01*
X1032871Y-117388D01*
X1031124Y-118263D01*
X1026758D01*
G01X1052991D02*
Y-106597D01*
G01Y-108638D02*
X1052118Y-107472D01*
X1050807Y-106888D01*
X1049279Y-106597D01*
X1047751Y-107180D01*
X1046441Y-108346D01*
X1045567Y-110096D01*
X1045131Y-112430D01*
X1045567Y-114763D01*
X1046441Y-116513D01*
X1047751Y-117680D01*
X1049279Y-118263D01*
X1050807Y-117971D01*
X1052118Y-117097D01*
X1052991Y-115930D01*
G01X1066561Y-100763D02*
Y-118263D01*
G01X1063504Y-106597D02*
X1069618D01*
G01X1080786Y-110388D02*
X1087773D01*
X1087118Y-108346D01*
X1086026Y-107180D01*
X1084498Y-106597D01*
X1082969Y-106888D01*
X1081659Y-107763D01*
X1080786Y-109805D01*
X1080349Y-111555D01*
Y-113305D01*
X1080786Y-115055D01*
X1081878Y-116805D01*
X1083188Y-117971D01*
X1084716Y-118263D01*
X1086244Y-117680D01*
X1087773Y-115930D01*
M02*
